# S9S_MB_2U (Grand Teton) — schematic netlist excerpt (pin names and nets, part order shuffled) for the footprints in the layout excerpt that follows; sources: Cadence DE-HDL packaged netlist, KiCad conversion of 03242023_DA0F0TMBIJ0_F0T_Motherboard_J_brd_V01_OCP.brd

R3467  Q_RES  10K 1% CHIP  pkg 0402LF  page 149 : A = RST_PERST_0_SWB_BUF_R_N ; B = GND

Q87  MOSFET_NCH_DUAL  PJT138K IC  pkg SOT363XD  page 255
  S1  = GND
  G1  = PWRGD_PCH_PWROK_R
  D2  = LED_PWRGD_SYS_PWROK_R_D
  S2  = GND
  G2  = PWRGD_SYS_PWROK_R
  D1  = LED_PWRGD_PCH_PWROK_R_D

(kicad_pcb
	(version 20260206)
	(generator "pcbnew")
	(generator_version "10.0")
	(general
		(thickness 1.6)
		(legacy_teardrops no)
	)
	(paper "A4")
	(title_block
		(title "03242023_DA0F0TMBIJ0_F0T_Motherboard_J_brd_V01_OCP.brd")
		(comment 1 "Grand Teton / footprints 3307-3308 of 6105")
	)
	(layers
		(0 "F.Cu" signal "TOP")
		(4 "In1.Cu" signal "GND")
		(6 "In2.Cu" signal "IN1")
		(8 "In3.Cu" signal "GND1")
		(10 "In4.Cu" signal "IN2")
		(12 "In5.Cu" signal "GND2")
		(14 "In6.Cu" signal "IN3")
		(16 "In7.Cu" signal "GND3")
		(18 "In8.Cu" signal "VCC")
		(20 "In9.Cu" signal "VCC1")
		(22 "In10.Cu" signal "GND4")
		(24 "In11.Cu" signal "IN4")
		(26 "In12.Cu" signal "GND5")
		(28 "In13.Cu" signal "IN5")
		(30 "In14.Cu" signal "GND6")
		(32 "In15.Cu" signal "IN6")
		(34 "In16.Cu" signal "GND7")
		(2 "B.Cu" signal "BOTTOM")
		(9 "F.Adhes" user "F.Adhesive")
		(11 "B.Adhes" user "B.Adhesive")
		(13 "F.Paste" user "Package Geometry/Pastemask Top")
		(15 "B.Paste" user "Package Geometry/Pastemask Bottom")
		(5 "F.SilkS" user "Ref Des/Silkscreen Top")
		(7 "B.SilkS" user "Ref Des/Silkscreen Bottom")
		(1 "F.Mask" user "Board Geometry/Soldermask Top")
		(3 "B.Mask" user "Board Geometry/Soldermask Bottom")
		(17 "Dwgs.User" user "User.Drawings")
		(19 "Cmts.User" user "User.Comments")
		(21 "Eco1.User" user "User.Eco1")
		(23 "Eco2.User" user "User.Eco2")
		(25 "Edge.Cuts" user "Board Geometry/Outline")
		(27 "Margin" user)
		(31 "F.CrtYd" user "Package Geometry/Place Bound Top")
		(29 "B.CrtYd" user "Package Geometry/Place Bound Bottom")
		(35 "F.Fab" user "Ref Des/Assembly Top")
		(33 "B.Fab" user "Ref Des/Assembly Bottom")
	)
	(footprint ""
		(layer "F.Cu")
		(at 100.924614 -96.123506)
		(property "Reference" "Q87"
			(at 1.59766 -0.765048 0)
			(unlocked yes)
			(layer "F.SilkS")
			(effects
				(font
					(size 0.7874 0.5842)
					(thickness 0.1524)
				)
				(justify left)
			)
		)
		(property "Value" ""
			(at 0 0 0)
			(layer "F.Fab")
			(effects
				(font
					(size 1.27 1.27)
				)
			)
		)
		(duplicate_pad_numbers_are_jumpers no)
		(fp_line
			(start -1.332738 -1.100074)
			(end -0.4826 -1.100074)
			(stroke
				(width 0.1524)
				(type default)
			)
			(layer "F.SilkS")
		)
		(fp_line
			(start -1.332738 1.100074)
			(end -1.332738 -1.100074)
			(stroke
				(width 0.1524)
				(type default)
			)
			(layer "F.SilkS")
		)
		(fp_line
			(start -0.4826 -1.100074)
			(end 0 -0.541274)
			(stroke
				(width 0.1524)
				(type default)
			)
			(layer "F.SilkS")
		)
		(fp_line
			(start 0 -0.541274)
			(end 0.4826 -1.100074)
			(stroke
				(width 0.1524)
				(type default)
			)
			(layer "F.SilkS")
		)
		(fp_line
			(start 0.4826 -1.100074)
			(end 1.332738 -1.100074)
			(stroke
				(width 0.1524)
				(type default)
			)
			(layer "F.SilkS")
		)
		(fp_line
			(start 1.332738 -1.100074)
			(end 1.332738 1.100074)
			(stroke
				(width 0.1524)
				(type default)
			)
			(layer "F.SilkS")
		)
		(fp_line
			(start 1.332738 1.100074)
			(end -1.332738 1.100074)
			(stroke
				(width 0.1524)
				(type default)
			)
			(layer "F.SilkS")
		)
		(fp_poly
			(pts
				(xy -0.600202 -1.933448) (xy -0.95123 -1.231392) (xy -1.302258 -1.933448)
			)
			(stroke
				(width 0)
				(type default)
			)
			(fill yes)
			(layer "F.SilkS")
		)
		(fp_line
			(start -0.674878 -1.100074)
			(end 0.674878 -1.100074)
			(stroke
				(width 0.1)
				(type default)
			)
			(layer "F.Fab")
		)
		(fp_line
			(start -0.674878 1.100074)
			(end -0.674878 -1.100074)
			(stroke
				(width 0.1)
				(type default)
			)
			(layer "F.Fab")
		)
		(fp_line
			(start 0.674878 -1.100074)
			(end 0.674878 1.100074)
			(stroke
				(width 0.1)
				(type default)
			)
			(layer "F.Fab")
		)
		(fp_line
			(start 0.674878 1.100074)
			(end -0.674878 1.100074)
			(stroke
				(width 0.1)
				(type default)
			)
			(layer "F.Fab")
		)
		(fp_poly
			(pts
				(xy -2.2352 -0.298958) (xy -2.2352 -1.001014) (xy -1.533144 -0.649986)
			)
			(stroke
				(width 0)
				(type default)
			)
			(fill yes)
			(layer "F.Fab")
		)
		(pad "1" smd rect
			(at -0.94996 -0.649986 90)
			(size 0.4318 0.508)
			(layers "F.Cu" "F.Mask" "F.Paste")
			(net "GND")
		)
		(pad "2" smd rect
			(at -0.94996 0 90)
			(size 0.4318 0.508)
			(layers "F.Cu" "F.Mask" "F.Paste")
			(net "PWRGD_PCH_PWROK_R")
		)
		(pad "3" smd rect
			(at -0.94996 0.649986 90)
			(size 0.4318 0.508)
			(layers "F.Cu" "F.Mask" "F.Paste")
			(net "LED_PWRGD_SYS_PWROK_R_D")
		)
		(pad "4" smd rect
			(at 0.94996 0.649986 90)
			(size 0.4318 0.508)
			(layers "F.Cu" "F.Mask" "F.Paste")
			(net "GND")
		)
		(pad "5" smd rect
			(at 0.94996 0 90)
			(size 0.4318 0.508)
			(layers "F.Cu" "F.Mask" "F.Paste")
			(net "PWRGD_SYS_PWROK_R")
		)
		(pad "6" smd rect
			(at 0.94996 -0.649986 90)
			(size 0.4318 0.508)
			(layers "F.Cu" "F.Mask" "F.Paste")
			(net "LED_PWRGD_PCH_PWROK_R_D")
		)
	)
	(footprint ""
		(layer "F.Cu")
		(at 31.29788 -428.843948)
		(property "Reference" "R3467"
			(at 0 0 0)
			(layer "F.SilkS")
			(hide yes)
			(effects
				(font
					(size 1.27 1.27)
				)
			)
		)
		(property "Value" ""
			(at 0 0 0)
			(layer "F.Fab")
			(effects
				(font
					(size 1.27 1.27)
				)
			)
		)
		(duplicate_pad_numbers_are_jumpers no)
		(fp_line
			(start -0.7874 -0.4064)
			(end 0.7874 -0.4064)
			(stroke
				(width 0.1524)
				(type default)
			)
			(layer "F.SilkS")
		)
		(fp_line
			(start -0.7874 0.4064)
			(end -0.7874 -0.4064)
			(stroke
				(width 0.1524)
				(type default)
			)
			(layer "F.SilkS")
		)
		(fp_line
			(start 0.7874 -0.4064)
			(end 0.7874 0.4064)
			(stroke
				(width 0.1524)
				(type default)
			)
			(layer "F.SilkS")
		)
		(fp_line
			(start 0.7874 0.4064)
			(end -0.7874 0.4064)
			(stroke
				(width 0.1524)
				(type default)
			)
			(layer "F.SilkS")
		)
		(fp_line
			(start -0.67945 -0.305054)
			(end -0.12065 -0.305054)
			(stroke
				(width 0.1)
				(type default)
			)
			(layer "F.Fab")
		)
		(fp_line
			(start -0.67945 0.3048)
			(end -0.67945 -0.305054)
			(stroke
				(width 0.1)
				(type default)
			)
			(layer "F.Fab")
		)
		(fp_line
			(start -0.12065 -0.305054)
			(end -0.12065 -0.2794)
			(stroke
				(width 0.1)
				(type default)
			)
			(layer "F.Fab")
		)
		(fp_line
			(start -0.12065 -0.2794)
			(end 0.12065 -0.2794)
			(stroke
				(width 0.1)
				(type default)
			)
			(layer "F.Fab")
		)
		(fp_line
			(start -0.12065 0.2794)
			(end -0.12065 0.3048)
			(stroke
				(width 0.1)
				(type default)
			)
			(layer "F.Fab")
		)
		(fp_line
			(start -0.12065 0.3048)
			(end -0.67945 0.3048)
			(stroke
				(width 0.1)
				(type default)
			)
			(layer "F.Fab")
		)
		(fp_line
			(start 0.120396 0.2794)
			(end -0.12065 0.2794)
			(stroke
				(width 0.1)
				(type default)
			)
			(layer "F.Fab")
		)
		(fp_line
			(start 0.120396 0.3048)
			(end 0.120396 0.2794)
			(stroke
				(width 0.1)
				(type default)
			)
			(layer "F.Fab")
		)
		(fp_line
			(start 0.12065 -0.3048)
			(end 0.67945 -0.3048)
			(stroke
				(width 0.1)
				(type default)
			)
			(layer "F.Fab")
		)
		(fp_line
			(start 0.12065 -0.2794)
			(end 0.12065 -0.3048)
			(stroke
				(width 0.1)
				(type default)
			)
			(layer "F.Fab")
		)
		(fp_line
			(start 0.67945 -0.3048)
			(end 0.67945 0.3048)
			(stroke
				(width 0.1)
				(type default)
			)
			(layer "F.Fab")
		)
		(fp_line
			(start 0.67945 0.3048)
			(end 0.120396 0.3048)
			(stroke
				(width 0.1)
				(type default)
			)
			(layer "F.Fab")
		)
		(pad "1" smd circle
			(at -0.40005 0)
			(size 0 0)
			(layers "F.Cu" "F.Mask" "F.Paste")
			(net "RST_PERST_0_SWB_BUF_R_N")
		)
		(pad "2" smd circle
			(at 0.40005 0)
			(size 0 0)
			(layers "F.Cu" "F.Mask" "F.Paste")
			(net "GND")
		)
	)
)
